# HDD Back Plane_Stackup.xlsx — PCB_Test_Coupon_Requirement (pcb-stackup)
| Project Test Coupon |  |  |  |  |  |  |  |
| 申請日期 |  | 申請者 |  | Peroject Name |  | 板號-版本 | 表單版本 |
|  |  |  |  | Tioga Pass Channel |  | 17301-SA | v1.0 |
| Test Coupon 設計需求/ Patten / Location |  |  |  |  |  |  |  |
| 項目 | 內容 | 需求 | Coupon 設計規範 | Coupon 位置 | 測試允收標準 | Tracking Code 格式/位置 | Tracking Code位置 |
| 1 | Impedence Coupon | ■YES  □NO | □依Gerber ■依廠商建議Coupon設計 □其它(請詳述或提供附件) | ■Board折斷邊(需填寫預留折斷邊寬度)        □ 折斷邊寬度至少: 40*60mm  □Working panel | ■+/-10% □Cpk: > 1.0 ■其它(請詳述或提供附件) | □無此項要求 ■有，Tracking code格式依廠商建議 □有，Tracking code格式依其他方式      (請詳述或提供附件) | ■PCB Board 內       □ 指定位置(請詳述)：       ■ 依廠商建議    ■Test Coupon |
| 2 | Delta-L Coupon | ■YES  □NO | □依Gerber ■依廠商建議Coupon設計 □其它(請詳述或提供附件) | ■Board折斷邊(需填寫預留折斷邊寬度)       □ 折斷邊寬度至少: 40*60mm  □Working panel | ■Failure Rate < 0.3% □Cpk: > 1.0 □其它(請詳述或提供附件) | □無此項要求 ■有，Tracking code格式依廠商建議 □有，Tracking code格式依其他方式      (請詳述或提供附件) | ■PCB Board 內       □ 指定位置(請詳述)：       ■ 依廠商建議    ■Test Coupon |
